# BASEBOARD_FAB2 (Tioga Pass) — schematic netlist excerpt (pin names and nets, part order shuffled) for the footprints in the layout excerpt that follows; sources: Cadence DE-HDL packaged netlist, KiCad conversion of Wiwynn_Tioga_Pass_MB.brd

C9U8  CAP  10UF 16V 10% X7R  pkg 0805  page 197 : A = P12V_NVDIMM_GHJ ; B = GND
C6L1  CAP_A  0.01UF 25V 10% X7R  pkg 0402V  page 53 : A = M_F_VREF ; B = GND
R8F6  RES  0.0 5% CHIP  pkg 0402  page 154 : A = SPI_PCH_MISO ; B = SPI_PCH_MISO_R

(kicad_pcb
	(version 20260206)
	(generator "pcbnew")
	(generator_version "10.0")
	(general
		(thickness 1.6)
		(legacy_teardrops no)
	)
	(paper "A4")
	(title_block
		(title "Wiwynn_Tioga_Pass_MB.brd")
		(comment 1 "Tioga Pass / footprints 2876-2878 of 4770")
	)
	(layers
		(0 "F.Cu" signal "TOP")
		(4 "In1.Cu" signal "L2GND")
		(6 "In2.Cu" signal "L3")
		(8 "In3.Cu" signal "L4GND")
		(10 "In4.Cu" signal "L5")
		(12 "In5.Cu" signal "L6GND")
		(14 "In6.Cu" signal "L7VCC")
		(16 "In7.Cu" signal "L8VCC")
		(18 "In8.Cu" signal "L9GND")
		(20 "In9.Cu" signal "L10")
		(22 "In10.Cu" signal "L11GND")
		(24 "In11.Cu" signal "L12")
		(26 "In12.Cu" signal "L13GND")
		(2 "B.Cu" signal "BOTTOM")
		(9 "F.Adhes" user "F.Adhesive")
		(11 "B.Adhes" user "B.Adhesive")
		(13 "F.Paste" user "Package Geometry/Pastemask Top")
		(15 "B.Paste" user "Package Geometry/Pastemask Bottom")
		(5 "F.SilkS" user "Ref Des/Silkscreen Top")
		(7 "B.SilkS" user "Ref Des/Silkscreen Bottom")
		(1 "F.Mask" user "Board Geometry/Soldermask Top")
		(3 "B.Mask" user "Board Geometry/Soldermask Bottom")
		(17 "Dwgs.User" user "User.Drawings")
		(19 "Cmts.User" user "User.Comments")
		(21 "Eco1.User" user "User.Eco1")
		(23 "Eco2.User" user "User.Eco2")
		(25 "Edge.Cuts" user "Board Geometry/Outline")
		(27 "Margin" user)
		(31 "F.CrtYd" user "Package Geometry/Place Bound Top")
		(29 "B.CrtYd" user "Package Geometry/Place Bound Bottom")
		(35 "F.Fab" user "Ref Des/Assembly Top")
		(33 "B.Fab" user "Ref Des/Assembly Bottom")
	)
	(footprint ""
		(layer "B.Cu")
		(at 375.285 -56.6039)
		(property "Reference" "R8F6"
			(at 0 0 0)
			(layer "B.SilkS")
			(hide yes)
			(effects
				(font
					(size 1.27 1.27)
				)
				(justify mirror)
			)
		)
		(property "Value" ""
			(at 0 0 0)
			(layer "B.Fab")
			(effects
				(font
					(size 1.27 1.27)
				)
				(justify mirror)
			)
		)
		(duplicate_pad_numbers_are_jumpers no)
		(fp_poly
			(pts
				(xy 0.2794 -0.1016) (xy -0.2794 -0.1016) (xy -0.2794 0.9906) (xy 0.2794 0.9906)
			)
			(stroke
				(width 0)
				(type default)
			)
			(fill no)
			(layer "B.CrtYd")
		)
		(fp_line
			(start -0.2794 -0.1016)
			(end 0.2794 -0.1016)
			(stroke
				(width 0.1)
				(type default)
			)
			(layer "B.Fab")
		)
		(fp_line
			(start -0.2794 0.9906)
			(end -0.2794 -0.1016)
			(stroke
				(width 0.1)
				(type default)
			)
			(layer "B.Fab")
		)
		(fp_line
			(start 0.2794 -0.1016)
			(end 0.2794 0.9906)
			(stroke
				(width 0.1)
				(type default)
			)
			(layer "B.Fab")
		)
		(fp_line
			(start 0.2794 0.9906)
			(end -0.2794 0.9906)
			(stroke
				(width 0.1)
				(type default)
			)
			(layer "B.Fab")
		)
		(pad "1" smd rect
			(at 0 0 180)
			(size 0.508 0.508)
			(layers "B.Cu" "B.Mask" "B.Paste")
			(net "SPI_PCH_MISO")
		)
		(pad "2" smd rect
			(at 0 0.889 180)
			(size 0.508 0.508)
			(layers "B.Cu" "B.Mask" "B.Paste")
			(net "SPI_PCH_MISO_R")
		)
		(zone
			(layer "B.Cu")
			(hatch none 0.5)
			(connect_pads
				(clearance 0)
			)
			(min_thickness 0.25)
			(keepout
				(tracks allowed)
				(vias not_allowed)
				(pads allowed)
				(copperpour not_allowed)
				(footprints allowed)
			)
			(placement
				(enabled no)
				(sheetname "")
			)
			(fill
				(thermal_gap 0.5)
				(thermal_bridge_width 0.5)
				(island_removal_mode 0)
			)
			(polygon
				(pts
					(xy 375.539 -56.3499) (xy 375.031 -56.3499) (xy 375.031 -55.9689) (xy 375.539 -55.9689)
				)
			)
		)
		(zone
			(layer "B.Cu")
			(hatch none 0.5)
			(connect_pads
				(clearance 0)
			)
			(min_thickness 0.25)
			(keepout
				(tracks not_allowed)
				(vias allowed)
				(pads allowed)
				(copperpour not_allowed)
				(footprints allowed)
			)
			(placement
				(enabled no)
				(sheetname "")
			)
			(fill
				(thermal_gap 0.5)
				(thermal_bridge_width 0.5)
				(island_removal_mode 0)
			)
			(polygon
				(pts
					(xy 375.539 -55.9689) (xy 375.031 -55.9689) (xy 375.031 -56.3499) (xy 375.539 -56.3499)
				)
			)
		)
	)
	(footprint ""
		(layer "B.Cu")
		(at 28.0924 -8.122412 -90)
		(property "Reference" "C9U8"
			(at 0 0 90)
			(layer "B.SilkS")
			(hide yes)
			(effects
				(font
					(size 1.27 1.27)
				)
				(justify mirror)
			)
		)
		(property "Value" ""
			(at 0 0 90)
			(layer "B.Fab")
			(effects
				(font
					(size 1.27 1.27)
				)
				(justify mirror)
			)
		)
		(duplicate_pad_numbers_are_jumpers no)
		(fp_rect
			(start 0.7239 -0.2159)
			(end -0.7239 1.9939)
			(stroke
				(width 0)
				(type default)
			)
			(fill no)
			(layer "B.CrtYd")
		)
		(fp_line
			(start -0.7239 1.9939)
			(end -0.7239 -0.2159)
			(stroke
				(width 0.1)
				(type default)
			)
			(layer "B.Fab")
		)
		(fp_line
			(start 0.7239 1.9939)
			(end -0.7239 1.9939)
			(stroke
				(width 0.1)
				(type default)
			)
			(layer "B.Fab")
		)
		(fp_line
			(start -0.7239 -0.2159)
			(end 0.7239 -0.2159)
			(stroke
				(width 0.1)
				(type default)
			)
			(layer "B.Fab")
		)
		(fp_line
			(start 0.7239 -0.2159)
			(end 0.7239 1.9939)
			(stroke
				(width 0.1)
				(type default)
			)
			(layer "B.Fab")
		)
		(pad "1" smd rect
			(at 0 0 90)
			(size 1.27 1.016)
			(layers "B.Cu" "B.Mask" "B.Paste")
			(net "P12V_NVDIMM_GHJ")
		)
		(pad "2" smd rect
			(at 0 1.778 90)
			(size 1.27 1.016)
			(layers "B.Cu" "B.Mask" "B.Paste")
			(net "GND")
		)
		(zone
			(layer "B.Cu")
			(hatch none 0.5)
			(connect_pads
				(clearance 0)
			)
			(min_thickness 0.25)
			(keepout
				(tracks not_allowed)
				(vias allowed)
				(pads allowed)
				(copperpour not_allowed)
				(footprints allowed)
			)
			(placement
				(enabled no)
				(sheetname "")
			)
			(fill
				(thermal_gap 0.5)
				(thermal_bridge_width 0.5)
				(island_removal_mode 0)
			)
			(polygon
				(pts
					(xy 27.5844 -7.487412) (xy 27.5844 -8.757412) (xy 26.8224 -8.757412) (xy 26.8224 -7.487412)
				)
			)
		)
	)
	(footprint ""
		(layer "B.Cu")
		(at 195.453 -154.6352 90)
		(property "Reference" "C6L1"
			(at 0 0 90)
			(layer "B.SilkS")
			(hide yes)
			(effects
				(font
					(size 1.27 1.27)
				)
				(justify mirror)
			)
		)
		(property "Value" ""
			(at 0 0 90)
			(layer "B.Fab")
			(effects
				(font
					(size 1.27 1.27)
				)
				(justify mirror)
			)
		)
		(duplicate_pad_numbers_are_jumpers no)
		(fp_poly
			(pts
				(xy -0.3048 -0.1016) (xy -0.3048 0.9906) (xy 0.3048 0.9906) (xy 0.3048 -0.1016)
			)
			(stroke
				(width 0)
				(type default)
			)
			(fill no)
			(layer "B.CrtYd")
		)
		(fp_line
			(start 0.3048 -0.1016)
			(end 0.3048 0.9906)
			(stroke
				(width 0.1)
				(type default)
			)
			(layer "B.Fab")
		)
		(fp_line
			(start -0.3048 -0.1016)
			(end 0.3048 -0.1016)
			(stroke
				(width 0.1)
				(type default)
			)
			(layer "B.Fab")
		)
		(fp_line
			(start 0.3048 0.9906)
			(end -0.3048 0.9906)
			(stroke
				(width 0.1)
				(type default)
			)
			(layer "B.Fab")
		)
		(fp_line
			(start -0.3048 0.9906)
			(end -0.3048 -0.1016)
			(stroke
				(width 0.1)
				(type default)
			)
			(layer "B.Fab")
		)
		(pad "1" smd rect
			(at 0 0 270)
			(size 0.508 0.508)
			(layers "B.Cu" "B.Mask" "B.Paste")
			(net "M_F_VREF")
		)
		(pad "2" smd rect
			(at 0 0.889 270)
			(size 0.508 0.508)
			(layers "B.Cu" "B.Mask" "B.Paste")
			(net "GND")
		)
		(zone
			(layer "B.Cu")
			(hatch none 0.5)
			(connect_pads
				(clearance 0)
			)
			(min_thickness 0.25)
			(keepout
				(tracks allowed)
				(vias not_allowed)
				(pads allowed)
				(copperpour not_allowed)
				(footprints allowed)
			)
			(placement
				(enabled no)
				(sheetname "")
			)
			(fill
				(thermal_gap 0.5)
				(thermal_bridge_width 0.5)
				(island_removal_mode 0)
			)
			(polygon
				(pts
					(xy 195.707 -154.8892) (xy 195.707 -154.3812) (xy 196.088 -154.3812) (xy 196.088 -154.8892)
				)
			)
		)
		(zone
			(layer "B.Cu")
			(hatch none 0.5)
			(connect_pads
				(clearance 0)
			)
			(min_thickness 0.25)
			(keepout
				(tracks not_allowed)
				(vias allowed)
				(pads allowed)
				(copperpour not_allowed)
				(footprints allowed)
			)
			(placement
				(enabled no)
				(sheetname "")
			)
			(fill
				(thermal_gap 0.5)
				(thermal_bridge_width 0.5)
				(island_removal_mode 0)
			)
			(polygon
				(pts
					(xy 196.088 -154.8892) (xy 196.088 -154.3812) (xy 195.707 -154.3812) (xy 195.707 -154.8892)
				)
			)
		)
	)
)
